(kicad_pcb
	(version 20260206)
	(generator "pcbnew")
	(generator_version "10.0")
	(general
		(thickness 1.6)
		(legacy_teardrops no)
	)
	(paper "A4")
	(title_block
		(title "peb — Lightning_PEB_BRD.brd")
		(comment 1 "Lightning (Wiwynn / Facebook NVMe JBOF) / footprints 632-639 of 2563")
	)
	(layers
		(0 "F.Cu" signal "TOP")
		(4 "In1.Cu" signal "L2GND")
		(6 "In2.Cu" signal "L3")
		(8 "In3.Cu" signal "L4VCC")
		(10 "In4.Cu" signal "L5VCC")
		(12 "In5.Cu" signal "L6")
		(14 "In6.Cu" signal "L7GND")
		(2 "B.Cu" signal "BOTTOM")
		(9 "F.Adhes" user "F.Adhesive")
		(11 "B.Adhes" user "B.Adhesive")
		(13 "F.Paste" user "Package Geometry/Pastemask Top")
		(15 "B.Paste" user "Package Geometry/Pastemask Bottom")
		(5 "F.SilkS" user "Ref Des/Silkscreen Top")
		(7 "B.SilkS" user "Ref Des/Silkscreen Bottom")
		(1 "F.Mask" user "Board Geometry/Soldermask Top")
		(3 "B.Mask" user "Board Geometry/Soldermask Bottom")
		(17 "Dwgs.User" user "User.Drawings")
		(19 "Cmts.User" user "User.Comments")
		(21 "Eco1.User" user "User.Eco1")
		(23 "Eco2.User" user "User.Eco2")
		(25 "Edge.Cuts" user "Board Geometry/Outline")
		(27 "Margin" user)
		(31 "F.CrtYd" user "Package Geometry/Place Bound Top")
		(29 "B.CrtYd" user "Package Geometry/Place Bound Bottom")
		(35 "F.Fab" user "Ref Des/Assembly Top")
		(33 "B.Fab" user "Ref Des/Assembly Bottom")
	)
	(footprint ""
		(layer "F.Cu")
		(at 69.3166 -74.93)
		(property "Reference" "R266"
			(at 0 0 0)
			(layer "F.SilkS")
			(hide yes)
			(effects
				(font
					(size 1.27 1.27)
				)
			)
		)
		(property "Value" "2K2R2J-2-GP"
			(at 0.064008 -3.993896 0)
			(unlocked yes)
			(layer "F.Fab")
			(hide yes)
			(effects
				(font
					(size 1.016 1.016)
					(thickness 0.1524)
				)
			)
		)
		(property "Device Type" "R402H16"
			(at 0.064008 -5.517896 0)
			(unlocked yes)
			(layer "F.Fab")
			(hide yes)
			(effects
				(font
					(size 1.016 1.016)
					(thickness 0.1524)
				)
			)
		)
		(duplicate_pad_numbers_are_jumpers no)
		(fp_line
			(start -0.508 -0.9398)
			(end -0.508 0.9398)
			(stroke
				(width 0.1524)
				(type default)
			)
			(layer "F.SilkS")
		)
		(fp_line
			(start 0.508 -0.9398)
			(end -0.508 -0.9398)
			(stroke
				(width 0.1524)
				(type default)
			)
			(layer "F.SilkS")
		)
		(fp_rect
			(start -0.508 0.9398)
			(end 0.508 -0.9398)
			(stroke
				(width 0)
				(type default)
			)
			(fill no)
			(layer "F.CrtYd")
		)
		(fp_rect
			(start -0.508 0.9398)
			(end 0.508 -0.9398)
			(stroke
				(width 0)
				(type default)
			)
			(fill no)
			(layer "F.Fab")
		)
		(pad "1" smd custom
			(at 0 -0.4445)
			(size 0.1397 0.1397)
			(layers "F.Cu" "F.Mask" "F.Paste")
			(net "P3V3_STBY")
			(options
				(clearance outline)
				(anchor circle)
			)
			(primitives
				(gr_poly
					(pts
						(arc
							(start -0.1778 -0.2794)
							(mid -0.249642 -0.249642)
							(end -0.2794 -0.1778)
						)
						(arc
							(start -0.2794 0.1778)
							(mid -0.249642 0.249642)
							(end -0.1778 0.2794)
						)
						(arc
							(start 0.1778 0.2794)
							(mid 0.249642 0.249642)
							(end 0.2794 0.1778)
						)
						(arc
							(start 0.2794 -0.1778)
							(mid 0.249642 -0.249642)
							(end 0.1778 -0.2794)
						)
					)
					(width 0)
					(fill yes)
				)
			)
		)
		(pad "2" smd custom
			(at 0 0.4445)
			(size 0.1397 0.1397)
			(layers "F.Cu" "F.Mask" "F.Paste")
			(net "PU_IBMC_BT_HOLD_N")
			(options
				(clearance outline)
				(anchor circle)
			)
			(primitives
				(gr_poly
					(pts
						(arc
							(start -0.1778 -0.2794)
							(mid -0.249642 -0.249642)
							(end -0.2794 -0.1778)
						)
						(arc
							(start -0.2794 0.1778)
							(mid -0.249642 0.249642)
							(end -0.1778 0.2794)
						)
						(arc
							(start 0.1778 0.2794)
							(mid 0.249642 0.249642)
							(end 0.2794 0.1778)
						)
						(arc
							(start 0.2794 -0.1778)
							(mid 0.249642 -0.249642)
							(end 0.1778 -0.2794)
						)
					)
					(width 0)
					(fill yes)
				)
			)
		)
	)
	(footprint ""
		(layer "F.Cu")
		(at 22.6568 -173.2026 90)
		(property "Reference" "R648"
			(at 0 0 90)
			(layer "F.SilkS")
			(hide yes)
			(effects
				(font
					(size 1.27 1.27)
				)
			)
		)
		(property "Value" "27KR2F-L-GP"
			(at 0.064008 -3.993896 90)
			(unlocked yes)
			(layer "F.Fab")
			(hide yes)
			(effects
				(font
					(size 1.016 1.016)
					(thickness 0.1524)
				)
			)
		)
		(property "Device Type" "R402H16"
			(at 0.064008 -5.517896 90)
			(unlocked yes)
			(layer "F.Fab")
			(hide yes)
			(effects
				(font
					(size 1.016 1.016)
					(thickness 0.1524)
				)
			)
		)
		(duplicate_pad_numbers_are_jumpers no)
		(fp_line
			(start 0.508 -0.9398)
			(end -0.508 -0.9398)
			(stroke
				(width 0.1524)
				(type default)
			)
			(layer "F.SilkS")
		)
		(fp_line
			(start -0.508 -0.9398)
			(end -0.508 0.9398)
			(stroke
				(width 0.1524)
				(type default)
			)
			(layer "F.SilkS")
		)
		(fp_rect
			(start -0.508 0.9398)
			(end 0.508 -0.9398)
			(stroke
				(width 0)
				(type default)
			)
			(fill no)
			(layer "F.CrtYd")
		)
		(fp_rect
			(start -0.508 0.9398)
			(end 0.508 -0.9398)
			(stroke
				(width 0)
				(type default)
			)
			(fill no)
			(layer "F.Fab")
		)
		(pad "1" smd custom
			(at 0 -0.4445 90)
			(size 0.1397 0.1397)
			(layers "F.Cu" "F.Mask" "F.Paste")
			(net "PCIE_MATED#_B")
			(options
				(clearance outline)
				(anchor circle)
			)
			(primitives
				(gr_poly
					(pts
						(arc
							(start -0.1778 -0.2794)
							(mid -0.249642 -0.249642)
							(end -0.2794 -0.1778)
						)
						(arc
							(start -0.2794 0.1778)
							(mid -0.249642 0.249642)
							(end -0.1778 0.2794)
						)
						(arc
							(start 0.1778 0.2794)
							(mid 0.249642 0.249642)
							(end 0.2794 0.1778)
						)
						(arc
							(start 0.2794 -0.1778)
							(mid 0.249642 -0.249642)
							(end 0.1778 -0.2794)
						)
					)
					(width 0)
					(fill yes)
				)
			)
		)
		(pad "2" smd custom
			(at 0 0.4445 90)
			(size 0.1397 0.1397)
			(layers "F.Cu" "F.Mask" "F.Paste")
			(net "P12V_PCIE")
			(options
				(clearance outline)
				(anchor circle)
			)
			(primitives
				(gr_poly
					(pts
						(arc
							(start -0.1778 -0.2794)
							(mid -0.249642 -0.249642)
							(end -0.2794 -0.1778)
						)
						(arc
							(start -0.2794 0.1778)
							(mid -0.249642 0.249642)
							(end -0.1778 0.2794)
						)
						(arc
							(start 0.1778 0.2794)
							(mid 0.249642 0.249642)
							(end 0.2794 0.1778)
						)
						(arc
							(start 0.2794 -0.1778)
							(mid 0.249642 -0.249642)
							(end 0.1778 -0.2794)
						)
					)
					(width 0)
					(fill yes)
				)
			)
		)
	)
	(footprint ""
		(layer "F.Cu")
		(at 45.936916 -113.454688 -90)
		(property "Reference" "R561"
			(at 0 0 270)
			(layer "F.SilkS")
			(hide yes)
			(effects
				(font
					(size 1.27 1.27)
				)
			)
		)
		(property "Value" "10KR2F-2-GP"
			(at 0.064008 -3.993896 270)
			(unlocked yes)
			(layer "F.Fab")
			(hide yes)
			(effects
				(font
					(size 1.016 1.016)
					(thickness 0.1524)
				)
			)
		)
		(property "Device Type" "R402H16"
			(at 0.064008 -5.517896 270)
			(unlocked yes)
			(layer "F.Fab")
			(hide yes)
			(effects
				(font
					(size 1.016 1.016)
					(thickness 0.1524)
				)
			)
		)
		(duplicate_pad_numbers_are_jumpers no)
		(fp_line
			(start -0.508 -0.9398)
			(end -0.508 0.9398)
			(stroke
				(width 0.1524)
				(type default)
			)
			(layer "F.SilkS")
		)
		(fp_line
			(start 0.508 -0.9398)
			(end -0.508 -0.9398)
			(stroke
				(width 0.1524)
				(type default)
			)
			(layer "F.SilkS")
		)
		(fp_rect
			(start -0.508 0.9398)
			(end 0.508 -0.9398)
			(stroke
				(width 0)
				(type default)
			)
			(fill no)
			(layer "F.CrtYd")
		)
		(fp_rect
			(start -0.508 0.9398)
			(end 0.508 -0.9398)
			(stroke
				(width 0)
				(type default)
			)
			(fill no)
			(layer "F.Fab")
		)
		(pad "1" smd custom
			(at 0 -0.4445 270)
			(size 0.1397 0.1397)
			(layers "F.Cu" "F.Mask" "F.Paste")
			(net "BMC_JTAG_L_EN")
			(options
				(clearance outline)
				(anchor circle)
			)
			(primitives
				(gr_poly
					(pts
						(arc
							(start -0.1778 -0.2794)
							(mid -0.249642 -0.249642)
							(end -0.2794 -0.1778)
						)
						(arc
							(start -0.2794 0.1778)
							(mid -0.249642 0.249642)
							(end -0.1778 0.2794)
						)
						(arc
							(start 0.1778 0.2794)
							(mid 0.249642 0.249642)
							(end 0.2794 0.1778)
						)
						(arc
							(start 0.2794 -0.1778)
							(mid 0.249642 -0.249642)
							(end 0.1778 -0.2794)
						)
					)
					(width 0)
					(fill yes)
				)
			)
		)
		(pad "2" smd custom
			(at 0 0.4445 270)
			(size 0.1397 0.1397)
			(layers "F.Cu" "F.Mask" "F.Paste")
			(net "GND")
			(options
				(clearance outline)
				(anchor circle)
			)
			(primitives
				(gr_poly
					(pts
						(arc
							(start -0.1778 -0.2794)
							(mid -0.249642 -0.249642)
							(end -0.2794 -0.1778)
						)
						(arc
							(start -0.2794 0.1778)
							(mid -0.249642 0.249642)
							(end -0.1778 0.2794)
						)
						(arc
							(start 0.1778 0.2794)
							(mid 0.249642 0.249642)
							(end 0.2794 0.1778)
						)
						(arc
							(start 0.2794 -0.1778)
							(mid 0.249642 -0.249642)
							(end 0.1778 -0.2794)
						)
					)
					(width 0)
					(fill yes)
				)
			)
		)
	)
	(footprint ""
		(layer "F.Cu")
		(at 50.362866 -126.04242)
		(property "Reference" "TP177"
			(at 0 0 0)
			(layer "F.SilkS")
			(hide yes)
			(effects
				(font
					(size 1.27 1.27)
				)
			)
		)
		(property "Value" "TPAD28-2-GP"
			(at -0.0127 -1.6637 0)
			(unlocked yes)
			(layer "F.Fab")
			(hide yes)
			(effects
				(font
					(size 1.016 1.016)
					(thickness 0.1524)
				)
			)
		)
		(property "Device Type" "TPAD28"
			(at -0.0127 -3.1877 0)
			(unlocked yes)
			(layer "F.Fab")
			(hide yes)
			(effects
				(font
					(size 1.016 1.016)
					(thickness 0.1524)
				)
			)
		)
		(duplicate_pad_numbers_are_jumpers no)
		(fp_poly
			(pts
				(arc
					(start 0.3556 0)
					(mid -0.3556 0)
					(end 0.3556 0)
				)
			)
			(stroke
				(width 0)
				(type default)
			)
			(fill no)
			(layer "F.CrtYd")
		)
		(fp_poly
			(pts
				(arc
					(start 0.6096 0)
					(mid -0.6096 0)
					(end 0.6096 0)
				)
			)
			(stroke
				(width 0)
				(type default)
			)
			(fill no)
			(layer "F.Fab")
		)
		(pad "1" smd circle
			(at 0 0)
			(size 0.7112 0.7112)
			(layers "F.Cu" "F.Mask" "F.Paste")
			(net "JTAG_BMC_TMS")
		)
	)
	(footprint ""
		(layer "F.Cu")
		(at 310.007 -65.5066)
		(property "Reference" "PG43"
			(at 0 0 0)
			(layer "F.SilkS")
			(hide yes)
			(effects
				(font
					(size 1.27 1.27)
				)
			)
		)
		(property "Value" "GAP-CLOSE-PWR-3-GP"
			(at 0.0254 -6.5786 0)
			(unlocked yes)
			(layer "F.Fab")
			(hide yes)
			(effects
				(font
					(size 1.016 1.016)
					(thickness 0.1524)
				)
			)
		)
		(property "Device Type" "GAP-CLOSE-PWR-3"
			(at 0.0254 -8.255 0)
			(unlocked yes)
			(layer "F.Fab")
			(hide yes)
			(effects
				(font
					(size 1.016 1.016)
					(thickness 0.1524)
				)
			)
		)
		(duplicate_pad_numbers_are_jumpers no)
		(fp_rect
			(start -0.7112 0.4572)
			(end 0.7112 -0.4572)
			(stroke
				(width 0)
				(type default)
			)
			(fill no)
			(layer "F.CrtYd")
		)
		(fp_poly
			(pts
				(xy -0.7112 -0.4572) (xy 0.7112 -0.4572) (xy 0.7112 0.4572) (xy -0.7112 0.4572)
			)
			(stroke
				(width 0)
				(type default)
			)
			(fill no)
			(layer "F.Fab")
		)
		(pad "1" smd rect
			(at -0.3048 0)
			(size 0.6604 0.762)
			(layers "F.Cu" "F.Mask" "F.Paste")
			(net "DUT_VDD")
		)
		(pad "2" smd rect
			(at 0.3048 0)
			(size 0.6604 0.762)
			(layers "F.Cu" "F.Mask" "F.Paste")
			(net "P0V9_E")
		)
	)
	(footprint ""
		(layer "F.Cu")
		(at 141.866874 -97.17532)
		(property "Reference" "PR75"
			(at 0 0 0)
			(layer "F.SilkS")
			(hide yes)
			(effects
				(font
					(size 1.27 1.27)
				)
			)
		)
		(property "Value" "0R2J-2-GP"
			(at 0.064008 -3.993896 0)
			(unlocked yes)
			(layer "F.Fab")
			(hide yes)
			(effects
				(font
					(size 1.016 1.016)
					(thickness 0.1524)
				)
			)
		)
		(property "Device Type" "R402H16"
			(at 0.064008 -5.517896 0)
			(unlocked yes)
			(layer "F.Fab")
			(hide yes)
			(effects
				(font
					(size 1.016 1.016)
					(thickness 0.1524)
				)
			)
		)
		(duplicate_pad_numbers_are_jumpers no)
		(fp_line
			(start -0.508 -0.9398)
			(end -0.508 0.9398)
			(stroke
				(width 0.1524)
				(type default)
			)
			(layer "F.SilkS")
		)
		(fp_line
			(start 0.508 -0.9398)
			(end -0.508 -0.9398)
			(stroke
				(width 0.1524)
				(type default)
			)
			(layer "F.SilkS")
		)
		(fp_rect
			(start -0.508 0.9398)
			(end 0.508 -0.9398)
			(stroke
				(width 0)
				(type default)
			)
			(fill no)
			(layer "F.CrtYd")
		)
		(fp_rect
			(start -0.508 0.9398)
			(end 0.508 -0.9398)
			(stroke
				(width 0)
				(type default)
			)
			(fill no)
			(layer "F.Fab")
		)
		(pad "1" smd custom
			(at 0 -0.4445)
			(size 0.1397 0.1397)
			(layers "F.Cu" "F.Mask" "F.Paste")
			(net "P5V_STBY")
			(options
				(clearance outline)
				(anchor circle)
			)
			(primitives
				(gr_poly
					(pts
						(arc
							(start -0.1778 -0.2794)
							(mid -0.249642 -0.249642)
							(end -0.2794 -0.1778)
						)
						(arc
							(start -0.2794 0.1778)
							(mid -0.249642 0.249642)
							(end -0.1778 0.2794)
						)
						(arc
							(start 0.1778 0.2794)
							(mid 0.249642 0.249642)
							(end 0.2794 0.1778)
						)
						(arc
							(start 0.2794 -0.1778)
							(mid 0.249642 -0.249642)
							(end 0.1778 -0.2794)
						)
					)
					(width 0)
					(fill yes)
				)
			)
		)
		(pad "2" smd custom
			(at 0 0.4445)
			(size 0.1397 0.1397)
			(layers "F.Cu" "F.Mask" "F.Paste")
			(net "VR_P1V8_STBY_BIAS")
			(options
				(clearance outline)
				(anchor circle)
			)
			(primitives
				(gr_poly
					(pts
						(arc
							(start -0.1778 -0.2794)
							(mid -0.249642 -0.249642)
							(end -0.2794 -0.1778)
						)
						(arc
							(start -0.2794 0.1778)
							(mid -0.249642 0.249642)
							(end -0.1778 0.2794)
						)
						(arc
							(start 0.1778 0.2794)
							(mid 0.249642 0.249642)
							(end 0.2794 0.1778)
						)
						(arc
							(start 0.2794 -0.1778)
							(mid 0.249642 -0.249642)
							(end 0.1778 -0.2794)
						)
					)
					(width 0)
					(fill yes)
				)
			)
		)
	)
	(footprint ""
		(layer "F.Cu")
		(at 156.718 -98.7044 180)
		(property "Reference" "R96"
			(at 0 0 180)
			(layer "F.SilkS")
			(hide yes)
			(effects
				(font
					(size 1.27 1.27)
				)
			)
		)
		(property "Value" "10KR2F-2-GP"
			(at 0.064008 -3.993896 180)
			(unlocked yes)
			(layer "F.Fab")
			(hide yes)
			(effects
				(font
					(size 1.016 1.016)
					(thickness 0.1524)
				)
			)
		)
		(property "Device Type" "R402H16"
			(at 0.064008 -5.517896 180)
			(unlocked yes)
			(layer "F.Fab")
			(hide yes)
			(effects
				(font
					(size 1.016 1.016)
					(thickness 0.1524)
				)
			)
		)
		(duplicate_pad_numbers_are_jumpers no)
		(fp_line
			(start 0.508 -0.9398)
			(end -0.508 -0.9398)
			(stroke
				(width 0.1524)
				(type default)
			)
			(layer "F.SilkS")
		)
		(fp_line
			(start -0.508 -0.9398)
			(end -0.508 0.9398)
			(stroke
				(width 0.1524)
				(type default)
			)
			(layer "F.SilkS")
		)
		(fp_rect
			(start -0.508 0.9398)
			(end 0.508 -0.9398)
			(stroke
				(width 0)
				(type default)
			)
			(fill no)
			(layer "F.CrtYd")
		)
		(fp_rect
			(start -0.508 0.9398)
			(end 0.508 -0.9398)
			(stroke
				(width 0)
				(type default)
			)
			(fill no)
			(layer "F.Fab")
		)
		(pad "1" smd custom
			(at 0 -0.4445 180)
			(size 0.1397 0.1397)
			(layers "F.Cu" "F.Mask" "F.Paste")
			(net "CLKGNE_SS_EN")
			(options
				(clearance outline)
				(anchor circle)
			)
			(primitives
				(gr_poly
					(pts
						(arc
							(start -0.1778 -0.2794)
							(mid -0.249642 -0.249642)
							(end -0.2794 -0.1778)
						)
						(arc
							(start -0.2794 0.1778)
							(mid -0.249642 0.249642)
							(end -0.1778 0.2794)
						)
						(arc
							(start 0.1778 0.2794)
							(mid 0.249642 0.249642)
							(end 0.2794 0.1778)
						)
						(arc
							(start 0.2794 -0.1778)
							(mid 0.249642 -0.249642)
							(end 0.1778 -0.2794)
						)
					)
					(width 0)
					(fill yes)
				)
			)
		)
		(pad "2" smd custom
			(at 0 0.4445 180)
			(size 0.1397 0.1397)
			(layers "F.Cu" "F.Mask" "F.Paste")
			(net "P1V8_STBY")
			(options
				(clearance outline)
				(anchor circle)
			)
			(primitives
				(gr_poly
					(pts
						(arc
							(start -0.1778 -0.2794)
							(mid -0.249642 -0.249642)
							(end -0.2794 -0.1778)
						)
						(arc
							(start -0.2794 0.1778)
							(mid -0.249642 0.249642)
							(end -0.1778 0.2794)
						)
						(arc
							(start 0.1778 0.2794)
							(mid 0.249642 0.249642)
							(end 0.2794 0.1778)
						)
						(arc
							(start 0.2794 -0.1778)
							(mid 0.249642 -0.249642)
							(end 0.1778 -0.2794)
						)
					)
					(width 0)
					(fill yes)
				)
			)
		)
	)
	(footprint ""
		(layer "F.Cu")
		(at 31.623 -53.721 -90)
		(property "Reference" "TC12"
			(at 0 0 270)
			(layer "F.SilkS")
			(hide yes)
			(effects
				(font
					(size 1.27 1.27)
				)
			)
		)
		(property "Value" "SC10U16V5KX-1-GP"
			(at -0.0762 -6.1214 270)
			(unlocked yes)
			(layer "F.Fab")
			(hide yes)
			(effects
				(font
					(size 1.016 1.016)
					(thickness 0.1524)
				)
			)
		)
		(property "Device Type" "C805H54"
			(at -0.0762 -8.1534 270)
			(unlocked yes)
			(layer "F.Fab")
			(hide yes)
			(effects
				(font
					(size 1.016 1.016)
					(thickness 0.1524)
				)
			)
		)
		(duplicate_pad_numbers_are_jumpers no)
		(fp_line
			(start 0.635 0)
			(end -0.635 0)
			(stroke
				(width 0.508)
				(type default)
			)
			(layer "F.SilkS")
		)
		(fp_rect
			(start -0.9652 1.778)
			(end 0.9652 -1.778)
			(stroke
				(width 0)
				(type default)
			)
			(fill no)
			(layer "F.CrtYd")
		)
		(fp_poly
			(pts
				(xy -0.9652 -1.778) (xy 0.9652 -1.778) (xy 0.9652 1.778) (xy -0.9652 1.778)
			)
			(stroke
				(width 0)
				(type default)
			)
			(fill no)
			(layer "F.Fab")
		)
		(pad "1" smd rect
			(at 0 -0.9652 270)
			(size 1.397 1.143)
			(layers "F.Cu" "F.Mask" "F.Paste")
			(net "P5V_USB")
		)
		(pad "2" smd rect
			(at 0 0.9652 270)
			(size 1.397 1.143)
			(layers "F.Cu" "F.Mask" "F.Paste")
			(net "GND")
		)
	)
)
